FILE_TYPE=LIBRARY_PARTS;
primitive 'SWITCH_D37771002','SWITCH_D37771002_SM';
  pin
    'PIN4':
      PIN_NUMBER='(4)';
      PINUSE='UNSPEC';
      NO_LOAD_CHECK='Both';
      NO_IO_CHECK='Both';
    'PIN3':
      PIN_NUMBER='(3)';
      PINUSE='UNSPEC';
      NO_LOAD_CHECK='Both';
      NO_IO_CHECK='Both';
    'PIN1':
      PIN_NUMBER='(1)';
      PINUSE='UNSPEC';
      NO_LOAD_CHECK='Both';
      NO_IO_CHECK='Both';
    'PIN2':
      PIN_NUMBER='(2)';
      PINUSE='UNSPEC';
      NO_LOAD_CHECK='Both';
      NO_IO_CHECK='Both';
  end_pin;
  body
    PART_NAME='SWITCH_D37771002';
    PHYS_DES_PREFIX='S';
  end_body;
end_primitive;

END.
